(kicad_pcb
	(version 20241229)
	(generator "pcbnew")
	(generator_version "9.0")
	(general
		(thickness 1.599998)
		(legacy_teardrops no)
	)
	(paper "A4")
	(title_block
		(date "2023-02-12")
		(rev "1.1.5")
		(comment 9 "footprints 133-135 of 473")
	)
	(layers
		(0 "F.Cu" signal)
		(4 "In1.Cu" power "In1.GND")
		(6 "In2.Cu" signal)
		(8 "In3.Cu" power "In3.GND")
		(10 "In4.Cu" power "In4.VCC")
		(12 "In5.Cu" signal)
		(14 "In6.Cu" power "In6.VCC")
		(2 "B.Cu" signal)
		(9 "F.Adhes" user "F.Adhesive")
		(11 "B.Adhes" user "B.Adhesive")
		(13 "F.Paste" user)
		(15 "B.Paste" user)
		(5 "F.SilkS" user "F.Silkscreen")
		(7 "B.SilkS" user "B.Silkscreen")
		(1 "F.Mask" user)
		(3 "B.Mask" user)
		(17 "Dwgs.User" user "User.Drawings")
		(19 "Cmts.User" user "User.Comments")
		(21 "Eco1.User" user "User.Eco1")
		(23 "Eco2.User" user "User.Eco2")
		(25 "Edge.Cuts" user)
		(27 "Margin" user)
		(31 "F.CrtYd" user "F.Courtyard")
		(29 "B.CrtYd" user "B.Courtyard")
		(35 "F.Fab" user)
		(33 "B.Fab" user)
	)
	(footprint "antmicro-footprints:QFN-48-1EP_7x7x0.9mm_P0.5mm_EP3.5x3.5mm"
		(layer "F.Cu")
		(at 200.436328 103.047157 90)
		(property "Reference" "U6"
			(at 0 -4.3 90)
			(layer "F.SilkS")
			(effects
				(font
					(size 0.7 0.7)
					(thickness 0.15)
				)
				(justify left bottom)
			)
		)
		(property "Value" "KSZ9031RNXCA"
			(at 0 5.1 90)
			(layer "F.Fab")
			(hide yes)
			(effects
				(font
					(size 0.7 0.7)
					(thickness 0.15)
				)
				(justify left bottom)
			)
		)
		(property "Description" "Ethernet Controller, 1000 Mbps, IEEE 802.3, 1.14 V, 3.465 V, QFN, 48 Pins"
			(at 0 0 90)
			(layer "F.Fab")
			(hide yes)
			(effects
				(font
					(size 1.27 1.27)
					(thickness 0.15)
				)
			)
		)
		(property "Author" "Antmicro"
			(at 303.483485 -97.389171 0)
			(layer "F.Fab")
			(hide yes)
			(effects
				(font
					(size 1 1)
					(thickness 0.15)
				)
			)
		)
		(property "License" "Apache-2.0"
			(at 303.483485 -97.389171 0)
			(layer "F.Fab")
			(hide yes)
			(effects
				(font
					(size 1 1)
					(thickness 0.15)
				)
			)
		)
		(property "MPN" "KSZ9031RNXCA"
			(at 303.483485 -97.389171 0)
			(layer "F.Fab")
			(hide yes)
			(effects
				(font
					(size 1 1)
					(thickness 0.15)
				)
			)
		)
		(property "Manufacturer" "Microchip Technology"
			(at 303.483485 -97.389171 0)
			(layer "F.Fab")
			(hide yes)
			(effects
				(font
					(size 1 1)
					(thickness 0.15)
				)
			)
		)
		(sheetname "Ethernet")
		(sheetfile "ethernet.kicad_sch")
		(attr smd)
		(fp_line
			(start 3.648 -3.65)
			(end 3.648 -3.25)
			(stroke
				(width 0.15)
				(type solid)
			)
			(layer "F.SilkS")
		)
		(fp_line
			(start 3.249 -3.65)
			(end 3.648 -3.65)
			(stroke
				(width 0.15)
				(type solid)
			)
			(layer "F.SilkS")
		)
		(fp_line
			(start -3.3 -3.65)
			(end -3.65 -3.65)
			(stroke
				(width 0.15)
				(type solid)
			)
			(layer "F.SilkS")
		)
		(fp_line
			(start -3.65 -3.3)
			(end -3.65 -3.65)
			(stroke
				(width 0.15)
				(type solid)
			)
			(layer "F.SilkS")
		)
		(fp_line
			(start 3.648 3.648)
			(end 3.648 3.249)
			(stroke
				(width 0.15)
				(type solid)
			)
			(layer "F.SilkS")
		)
		(fp_line
			(start 3.249 3.648)
			(end 3.648 3.648)
			(stroke
				(width 0.15)
				(type solid)
			)
			(layer "F.SilkS")
		)
		(fp_line
			(start -3.25 3.648)
			(end -3.65 3.648)
			(stroke
				(width 0.15)
				(type solid)
			)
			(layer "F.SilkS")
		)
		(fp_line
			(start -3.65 3.648)
			(end -3.65 3.249)
			(stroke
				(width 0.15)
				(type solid)
			)
			(layer "F.SilkS")
		)
		(fp_circle
			(center -3.7 -3.05)
			(end -3.65 -3.05)
			(stroke
				(width 0.15)
				(type solid)
			)
			(fill yes)
			(layer "F.SilkS")
		)
		(fp_rect
			(start -4.15 -4.15)
			(end 4.15 4.15)
			(stroke
				(width 0.05)
				(type solid)
			)
			(fill no)
			(layer "F.CrtYd")
		)
		(fp_line
			(start 3.499 -3.5)
			(end -2.5 -3.5)
			(stroke
				(width 0.15)
				(type solid)
			)
			(layer "F.Fab")
		)
		(fp_line
			(start -2.5 -3.5)
			(end -3.5 -2.5)
			(stroke
				(width 0.15)
				(type solid)
			)
			(layer "F.Fab")
		)
		(fp_line
			(start -3.5 -2.5)
			(end -3.5 3.499)
			(stroke
				(width 0.15)
				(type solid)
			)
			(layer "F.Fab")
		)
		(fp_line
			(start 3.499 3.499)
			(end 3.499 -3.5)
			(stroke
				(width 0.15)
				(type solid)
			)
			(layer "F.Fab")
		)
		(fp_line
			(start -3.5 3.499)
			(end 3.499 3.499)
			(stroke
				(width 0.15)
				(type solid)
			)
			(layer "F.Fab")
		)
		(pad "1" smd oval
			(at -3.5 -2.75 180)
			(size 0.3 0.9)
			(layers "F.Cu" "F.Mask" "F.Paste")
			(net 531 "/Ethernet/AVDDH")
			(pinfunction "AVDDH")
			(pintype "power_in")
		)
		(pad "2" smd oval
			(at -3.5 -2.25 180)
			(size 0.3 0.9)
			(layers "F.Cu" "F.Mask" "F.Paste")
			(net 522 "/Ethernet/ETH1_P")
			(pinfunction "TXRXP_A")
			(pintype "bidirectional")
		)
		(pad "3" smd oval
			(at -3.5 -1.75 180)
			(size 0.3 0.9)
			(layers "F.Cu" "F.Mask" "F.Paste")
			(net 525 "/Ethernet/ETH1_N")
			(pinfunction "TXRXM_A")
			(pintype "bidirectional")
		)
		(pad "4" smd oval
			(at -3.5 -1.25 180)
			(size 0.3 0.9)
			(layers "F.Cu" "F.Mask" "F.Paste")
			(net 529 "/Ethernet/AVDDL")
			(pinfunction "AVDDL")
			(pintype "power_in")
		)
		(pad "5" smd oval
			(at -3.5 -0.75 180)
			(size 0.3 0.9)
			(layers "F.Cu" "F.Mask" "F.Paste")
			(net 520 "/Ethernet/ETH2_P")
			(pinfunction "TXRXP_B")
			(pintype "bidirectional")
		)
		(pad "6" smd oval
			(at -3.5 -0.25 180)
			(size 0.3 0.9)
			(layers "F.Cu" "F.Mask" "F.Paste")
			(net 524 "/Ethernet/ETH2_N")
			(pinfunction "TXRXM_B")
			(pintype "bidirectional")
		)
		(pad "7" smd oval
			(at -3.5 0.248 180)
			(size 0.3 0.9)
			(layers "F.Cu" "F.Mask" "F.Paste")
			(net 519 "/Ethernet/ETH3_P")
			(pinfunction "TXRXP_C")
			(pintype "bidirectional")
		)
		(pad "8" smd oval
			(at -3.5 0.748 180)
			(size 0.3 0.9)
			(layers "F.Cu" "F.Mask" "F.Paste")
			(net 526 "/Ethernet/ETH3_N")
			(pinfunction "TXRXM_C")
			(pintype "bidirectional")
		)
		(pad "9" smd oval
			(at -3.5 1.249 180)
			(size 0.3 0.9)
			(layers "F.Cu" "F.Mask" "F.Paste")
			(net 529 "/Ethernet/AVDDL")
			(pinfunction "AVDDL")
			(pintype "passive")
		)
		(pad "10" smd oval
			(at -3.5 1.749 180)
			(size 0.3 0.9)
			(layers "F.Cu" "F.Mask" "F.Paste")
			(net 523 "/Ethernet/ETH4_P")
			(pinfunction "TXRXP_D")
			(pintype "bidirectional")
		)
		(pad "11" smd oval
			(at -3.5 2.249 180)
			(size 0.3 0.9)
			(layers "F.Cu" "F.Mask" "F.Paste")
			(net 527 "/Ethernet/ETH4_N")
			(pinfunction "TXRXM_D")
			(pintype "bidirectional")
		)
		(pad "12" smd oval
			(at -3.5 2.749 180)
			(size 0.3 0.9)
			(layers "F.Cu" "F.Mask" "F.Paste")
			(net 531 "/Ethernet/AVDDH")
			(pinfunction "AVDDH")
			(pintype "passive")
		)
		(pad "13" smd oval
			(at -2.75 3.499 90)
			(size 0.3 0.9)
			(layers "F.Cu" "F.Mask" "F.Paste")
			(net 638 "unconnected-(U6-NC-Pad13)")
			(pinfunction "NC")
			(pintype "no_connect")
		)
		(pad "14" smd oval
			(at -2.25 3.499 90)
			(size 0.3 0.9)
			(layers "F.Cu" "F.Mask" "F.Paste")
			(net 602 "1V2_SYS")
			(pinfunction "DVDDL")
			(pintype "power_in")
		)
		(pad "15" smd oval
			(at -1.75 3.499 90)
			(size 0.3 0.9)
			(layers "F.Cu" "F.Mask" "F.Paste")
			(net 13 "LED_SPD")
			(pinfunction "LED2/PHYAD1")
			(pintype "bidirectional")
		)
		(pad "16" smd oval
			(at -1.25 3.499 90)
			(size 0.3 0.9)
			(layers "F.Cu" "F.Mask" "F.Paste")
			(net 459 "3V3_SYS")
			(pinfunction "DVDDH")
			(pintype "power_in")
		)
		(pad "17" smd oval
			(at -0.75 3.499 90)
			(size 0.3 0.9)
			(layers "F.Cu" "F.Mask" "F.Paste")
			(net 12 "LED_LINK")
			(pinfunction "LED1/PHAD0/PME_N1")
			(pintype "bidirectional")
		)
		(pad "18" smd oval
			(at -0.25 3.499 90)
			(size 0.3 0.9)
			(layers "F.Cu" "F.Mask" "F.Paste")
			(net 602 "1V2_SYS")
			(pinfunction "DVDDL")
			(pintype "passive")
		)
		(pad "19" smd oval
			(at 0.248 3.499 90)
			(size 0.3 0.9)
			(layers "F.Cu" "F.Mask" "F.Paste")
			(net 32 "ETH_TXD0")
			(pinfunction "TXD0")
			(pintype "input")
		)
		(pad "20" smd oval
			(at 0.748 3.499 90)
			(size 0.3 0.9)
			(layers "F.Cu" "F.Mask" "F.Paste")
			(net 27 "ETH_TXD1")
			(pinfunction "TXD1")
			(pintype "input")
		)
		(pad "21" smd oval
			(at 1.249 3.499 90)
			(size 0.3 0.9)
			(layers "F.Cu" "F.Mask" "F.Paste")
			(net 28 "ETH_TXD2")
			(pinfunction "TXD2")
			(pintype "input")
		)
		(pad "22" smd oval
			(at 1.749 3.499 90)
			(size 0.3 0.9)
			(layers "F.Cu" "F.Mask" "F.Paste")
			(net 29 "ETH_TXD3")
			(pinfunction "TXD3")
			(pintype "input")
		)
		(pad "23" smd oval
			(at 2.249 3.499 90)
			(size 0.3 0.9)
			(layers "F.Cu" "F.Mask" "F.Paste")
			(net 602 "1V2_SYS")
			(pinfunction "DVDDL")
			(pintype "passive")
		)
		(pad "24" smd oval
			(at 2.749 3.499 90)
			(size 0.3 0.9)
			(layers "F.Cu" "F.Mask" "F.Paste")
			(net 30 "ETH_TX_CLK")
			(pinfunction "GTX_CLK")
			(pintype "input")
		)
		(pad "25" smd oval
			(at 3.499 2.749 180)
			(size 0.3 0.9)
			(layers "F.Cu" "F.Mask" "F.Paste")
			(net 31 "ETH_TX_EN")
			(pinfunction "TX_EN")
			(pintype "input")
		)
		(pad "26" smd oval
			(at 3.499 2.249 180)
			(size 0.3 0.9)
			(layers "F.Cu" "F.Mask" "F.Paste")
			(net 602 "1V2_SYS")
			(pinfunction "DVDDL")
			(pintype "passive")
		)
		(pad "27" smd oval
			(at 3.499 1.749 180)
			(size 0.3 0.9)
			(layers "F.Cu" "F.Mask" "F.Paste")
			(net 33 "ETH_RXD3")
			(pinfunction "RXD3/MODE3")
			(pintype "input")
		)
		(pad "28" smd oval
			(at 3.499 1.249 180)
			(size 0.3 0.9)
			(layers "F.Cu" "F.Mask" "F.Paste")
			(net 37 "ETH_RXD2")
			(pinfunction "RXD2/MODE2")
			(pintype "input")
		)
		(pad "29" smd oval
			(at 3.499 0.748 180)
			(size 0.3 0.9)
			(layers "F.Cu" "F.Mask" "F.Paste")
			(net 5 "GND")
			(pinfunction "VSS")
			(pintype "power_in")
		)
		(pad "30" smd oval
			(at 3.499 0.248 180)
			(size 0.3 0.9)
			(layers "F.Cu" "F.Mask" "F.Paste")
			(net 602 "1V2_SYS")
			(pinfunction "DVDDL")
			(pintype "passive")
		)
		(pad "31" smd oval
			(at 3.499 -0.25 180)
			(size 0.3 0.9)
			(layers "F.Cu" "F.Mask" "F.Paste")
			(net 23 "ETH_RXD1")
			(pinfunction "RXD1/MODE1")
			(pintype "input")
		)
		(pad "32" smd oval
			(at 3.499 -0.75 180)
			(size 0.3 0.9)
			(layers "F.Cu" "F.Mask" "F.Paste")
			(net 22 "ETH_RXD0")
			(pinfunction "RXD0/MODE0")
			(pintype "input")
		)
		(pad "33" smd oval
			(at 3.499 -1.25 180)
			(size 0.3 0.9)
			(layers "F.Cu" "F.Mask" "F.Paste")
			(net 34 "ETH_RX_DV")
			(pinfunction "RX_DV/CLK125_EN")
			(pintype "input")
		)
		(pad "34" smd oval
			(at 3.499 -1.75 180)
			(size 0.3 0.9)
			(layers "F.Cu" "F.Mask" "F.Paste")
			(net 459 "3V3_SYS")
			(pinfunction "DVDDH")
			(pintype "passive")
		)
		(pad "35" smd oval
			(at 3.499 -2.25 180)
			(size 0.3 0.9)
			(layers "F.Cu" "F.Mask" "F.Paste")
			(net 36 "ETH_RX_CLK")
			(pinfunction "RX_CLK/PHYAD2")
			(pintype "input")
		)
		(pad "36" smd oval
			(at 3.499 -2.75 180)
			(size 0.3 0.9)
			(layers "F.Cu" "F.Mask" "F.Paste")
			(net 35 "ETH_MDC")
			(pinfunction "MDC")
			(pintype "input")
		)
		(pad "37" smd oval
			(at 2.749 -3.5 90)
			(size 0.3 0.9)
			(layers "F.Cu" "F.Mask" "F.Paste")
			(net 25 "ETH_MDIO")
			(pinfunction "MDIO")
			(pintype "input")
		)
		(pad "38" smd oval
			(at 2.249 -3.5 90)
			(size 0.3 0.9)
			(layers "F.Cu" "F.Mask" "F.Paste")
			(net 541 "ETH_INT_N")
			(pinfunction "~{INT/PME}")
			(pintype "input")
		)
		(pad "39" smd oval
			(at 1.749 -3.5 90)
			(size 0.3 0.9)
			(layers "F.Cu" "F.Mask" "F.Paste")
			(net 602 "1V2_SYS")
			(pinfunction "DVDDL")
			(pintype "passive")
		)
		(pad "40" smd oval
			(at 1.249 -3.5 90)
			(size 0.3 0.9)
			(layers "F.Cu" "F.Mask" "F.Paste")
			(net 459 "3V3_SYS")
			(pinfunction "DVDDH")
			(pintype "passive")
		)
		(pad "41" smd oval
			(at 0.748 -3.5 90)
			(size 0.3 0.9)
			(layers "F.Cu" "F.Mask" "F.Paste")
			(net 26 "ETH_REF_CLK")
			(pinfunction "CLK125_NDO/LED_MODE")
			(pintype "input")
		)
		(pad "42" smd oval
			(at 0.248 -3.5 90)
			(size 0.3 0.9)
			(layers "F.Cu" "F.Mask" "F.Paste")
			(net 24 "ETH_RSTN")
			(pinfunction "~{RESET}")
			(pintype "input")
		)
		(pad "43" smd oval
			(at -0.25 -3.5 90)
			(size 0.3 0.9)
			(layers "F.Cu" "F.Mask" "F.Paste")
			(net 642 "unconnected-(U6-LDO_O-Pad43)")
			(pinfunction "LDO_O")
			(pintype "input+no_connect")
		)
		(pad "44" smd oval
			(at -0.75 -3.5 90)
			(size 0.3 0.9)
			(layers "F.Cu" "F.Mask" "F.Paste")
			(net 530 "/Ethernet/AVDDL_PLL")
			(pinfunction "AVDDL_PLL")
			(pintype "power_in")
		)
		(pad "45" smd oval
			(at -1.25 -3.5 90)
			(size 0.3 0.9)
			(layers "F.Cu" "F.Mask" "F.Paste")
			(net 656 "ETH_XO")
			(pinfunction "XO")
			(pintype "input")
		)
		(pad "46" smd oval
			(at -1.75 -3.5 90)
			(size 0.3 0.9)
			(layers "F.Cu" "F.Mask" "F.Paste")
			(net 657 "ETH_XI")
			(pinfunction "XI")
			(pintype "input")
		)
		(pad "47" smd oval
			(at -2.25 -3.5 90)
			(size 0.3 0.9)
			(layers "F.Cu" "F.Mask" "F.Paste")
			(net 645 "unconnected-(U6-NC-Pad47)")
			(pinfunction "NC")
			(pintype "no_connect")
		)
		(pad "48" smd oval
			(at -2.75 -3.5 90)
			(size 0.3 0.9)
			(layers "F.Cu" "F.Mask" "F.Paste")
			(net 261 "Net-(U6-ISET)")
			(pinfunction "ISET")
			(pintype "output")
		)
		(pad "49" smd rect
			(at 0 0 90)
			(size 3.5 3.5)
			(layers "F.Cu" "F.Mask" "F.Paste")
			(net 5 "GND")
			(pinfunction "PAD_GND")
			(pintype "power_in")
		)
	)
	(footprint "antmicro-footprints:Resonator_SMD_Abracon_ABM8G_3.2x2.5mm"
		(layer "F.Cu")
		(at 190.686328 105.274306 180)
		(property "Reference" "Y2"
			(at 3.286328 -0.325694 0)
			(layer "F.SilkS")
			(effects
				(font
					(size 0.7 0.7)
					(thickness 0.15)
				)
				(justify left bottom)
			)
		)
		(property "Value" "Oscillator_SMD_25MHz_KX-7"
			(at -1.75 2.548 180)
			(layer "F.Fab")
			(effects
				(font
					(size 0.7 0.7)
					(thickness 0.15)
				)
				(justify left bottom)
			)
		)
		(property "Description" "Crystal, 25 MHz, SMD, 3.2mm x 2.5mm, 30 ppm, 18 pF, 20 ppm, ABM8G"
			(at 0 0 180)
			(layer "F.Fab")
			(hide yes)
			(effects
				(font
					(size 1.27 1.27)
					(thickness 0.15)
				)
			)
		)
		(property "Author" "Antmicro"
			(at 381.372656 210.548612 0)
			(layer "F.Fab")
			(hide yes)
			(effects
				(font
					(size 1 1)
					(thickness 0.15)
				)
			)
		)
		(property "License" "Apache-2.0"
			(at 381.372656 210.548612 0)
			(layer "F.Fab")
			(hide yes)
			(effects
				(font
					(size 1 1)
					(thickness 0.15)
				)
			)
		)
		(property "MPN" "ABM8G-25.000MHZ-18-D2Y-T3"
			(at 381.372656 210.548612 0)
			(layer "F.Fab")
			(hide yes)
			(effects
				(font
					(size 1 1)
					(thickness 0.15)
				)
			)
		)
		(property "Manufacturer" "Abracon"
			(at 381.372656 210.548612 0)
			(layer "F.Fab")
			(hide yes)
			(effects
				(font
					(size 1 1)
					(thickness 0.15)
				)
			)
		)
		(property "Val" "25 MHz"
			(at 381.372656 210.548612 0)
			(layer "F.Fab")
			(hide yes)
			(effects
				(font
					(size 1 1)
					(thickness 0.15)
				)
			)
		)
		(sheetname "Ethernet")
		(sheetfile "ethernet.kicad_sch")
		(attr smd)
		(fp_line
			(start 1.6 0.3)
			(end 1.6 -0.2)
			(stroke
				(width 0.15)
				(type solid)
			)
			(layer "F.SilkS")
		)
		(fp_line
			(start -0.35 1.25)
			(end 0.45 1.25)
			(stroke
				(width 0.15)
				(type solid)
			)
			(layer "F.SilkS")
		)
		(fp_line
			(start -0.35 -1.25)
			(end 0.45 -1.25)
			(stroke
				(width 0.15)
				(type solid)
			)
			(layer "F.SilkS")
		)
		(fp_line
			(start -1.6 0.3)
			(end -1.6 -0.2)
			(stroke
				(width 0.15)
				(type solid)
			)
			(layer "F.SilkS")
		)
		(fp_circle
			(center -1.75 1.5)
			(end -1.7 1.5)
			(stroke
				(width 0.15)
				(type solid)
			)
			(fill no)
			(layer "F.SilkS")
		)
		(fp_rect
			(start -1.907 -1.55)
			(end 2.006 1.649)
			(stroke
				(width 0.05)
				(type solid)
			)
			(fill no)
			(layer "F.CrtYd")
		)
		(pad "1" smd roundrect
			(at -1.101 0.949 180)
			(size 1.3 1.1)
			(layers "F.Cu" "F.Mask" "F.Paste")
			(roundrect_rratio 0)
			(chamfer_ratio 0.2)
			(chamfer bottom_left)
			(net 656 "ETH_XO")
			(pintype "passive")
		)
		(pad "2" smd rect
			(at 1.199 0.949 180)
			(size 1.3 1.1)
			(layers "F.Cu" "F.Mask" "F.Paste")
			(net 5 "GND")
			(pinfunction "SH")
			(pintype "passive")
		)
		(pad "3" smd rect
			(at 1.199 -0.85 180)
			(size 1.3 1.1)
			(layers "F.Cu" "F.Mask" "F.Paste")
			(net 657 "ETH_XI")
			(pintype "passive")
		)
		(pad "4" smd rect
			(at -1.101 -0.85 180)
			(size 1.3 1.1)
			(layers "F.Cu" "F.Mask" "F.Paste")
			(net 5 "GND")
			(pinfunction "SH")
			(pintype "passive")
		)
	)
	(footprint "antmicro-footprints:R_0402_1005Metric"
		(layer "F.Cu")
		(at 180.1885 117.001)
		(descr "Resistor SMD 0402")
		(tags "resistor SMD 0402")
		(property "Reference" "R49"
			(at 0.8115 0.399 0)
			(layer "F.SilkS")
			(effects
				(font
					(size 0.7 0.7)
					(thickness 0.15)
				)
				(justify left bottom)
			)
		)
		(property "Value" "R_0R_0402"
			(at 0 1.4 0)
			(layer "F.Fab")
			(effects
				(font
					(size 0.7 0.7)
					(thickness 0.15)
				)
				(justify left bottom)
			)
		)
		(property "Description" "0R resistor in 0402 package with unspecified tolerance"
			(at 0 0 0)
			(layer "F.Fab")
			(hide yes)
			(effects
				(font
					(size 1.27 1.27)
					(thickness 0.15)
				)
			)
		)
		(property "Author" "Antmicro"
			(at 0 0 0)
			(layer "F.Fab")
			(hide yes)
			(effects
				(font
					(size 1 1)
					(thickness 0.15)
				)
			)
		)
		(property "Current" "1A"
			(at 0 0 0)
			(layer "F.Fab")
			(hide yes)
			(effects
				(font
					(size 1 1)
					(thickness 0.15)
				)
			)
		)
		(property "License" "Apache-2.0"
			(at 0 0 0)
			(layer "F.Fab")
			(hide yes)
			(effects
				(font
					(size 1 1)
					(thickness 0.15)
				)
			)
		)
		(property "MPN" "ERJ2GE0R00X"
			(at 0 0 0)
			(layer "F.Fab")
			(hide yes)
			(effects
				(font
					(size 1 1)
					(thickness 0.15)
				)
			)
		)
		(property "Manufacturer" "Panasonic"
			(at 0 0 0)
			(layer "F.Fab")
			(hide yes)
			(effects
				(font
					(size 1 1)
					(thickness 0.15)
				)
			)
		)
		(property "Tolerance" ""
			(at 0 0 0)
			(layer "F.Fab")
			(hide yes)
			(effects
				(font
					(size 1 1)
					(thickness 0.15)
				)
			)
		)
		(property "Val" "0R"
			(at 0 0 0)
			(layer "F.Fab")
			(hide yes)
			(effects
				(font
					(size 1 1)
					(thickness 0.15)
				)
			)
		)
		(sheetname "Config SPI flash")
		(sheetfile "config-spi.kicad_sch")
		(attr smd)
		(fp_rect
			(start -0.93 -0.47)
			(end 0.93 0.47)
			(stroke
				(width 0.05)
				(type solid)
			)
			(fill no)
			(layer "F.CrtYd")
		)
		(fp_rect
			(start -0.5 -0.25)
			(end 0.5 0.25)
			(stroke
				(width 0.15)
				(type solid)
			)
			(fill no)
			(layer "F.Fab")
		)
		(pad "1" smd roundrect
			(at -0.485 0)
			(size 0.59 0.64)
			(layers "F.Cu" "F.Mask" "F.Paste")
			(roundrect_rratio 0.25)
			(net 257 "Net-(U5-*HOLD{slash}IO3)")
			(pintype "passive")
		)
		(pad "2" smd roundrect
			(at 0.485 0)
			(size 0.59 0.64)
			(layers "F.Cu" "F.Mask" "F.Paste")
			(roundrect_rratio 0.25)
			(net 18 "QSPI_DQ3")
			(pintype "passive")
		)
	)
)
